G04 #@! TF.GenerationSoftware,KiCad,Pcbnew,(5.0.1)-3*
G04 #@! TF.CreationDate,2019-04-10T15:36:06+02:00*
G04 #@! TF.ProjectId,discovery,646973636F766572792E6B696361645F,rev?*
G04 #@! TF.SameCoordinates,PX4c4640PY8a48028*
G04 #@! TF.FileFunction,Legend,Bot*
G04 #@! TF.FilePolarity,Positive*
%FSLAX46Y46*%
G04 Gerber Fmt 4.6, Leading zero omitted, Abs format (unit mm)*
%MOMM*%
%LPD*%
G01*
G04 APERTURE LIST*
G04 APERTURE END LIST*
M02*
